# S9S_MB_2U (Grand Teton) — schematic netlist excerpt (pin names and nets, part order shuffled) for the footprints in the layout excerpt that follows; sources: Cadence DE-HDL packaged netlist, KiCad conversion of 03242023_DA0F0TMBIJ0_F0T_Motherboard_J_brd_V01_OCP.brd

R4573  Q_RES  0 5% EMPTY  pkg 0402LF  page 146 : A = PRSNT_CABLE_GPU_B3_N ; B = PRSNT_CABLE_GPU_B3_ISO_N
R4138  Q_RES  4.7K 5% CHIP  pkg 0402LF  page 146 : A = P3V3_AUX ; B = GPU_3V3IO_RSVD5_FFU_N

(kicad_pcb
	(version 20260206)
	(generator "pcbnew")
	(generator_version "10.0")
	(general
		(thickness 1.6)
		(legacy_teardrops no)
	)
	(paper "A4")
	(title_block
		(title "03242023_DA0F0TMBIJ0_F0T_Motherboard_J_brd_V01_OCP.brd")
		(comment 1 "Grand Teton / footprints 3577-3578 of 6105")
	)
	(layers
		(0 "F.Cu" signal "TOP")
		(4 "In1.Cu" signal "GND")
		(6 "In2.Cu" signal "IN1")
		(8 "In3.Cu" signal "GND1")
		(10 "In4.Cu" signal "IN2")
		(12 "In5.Cu" signal "GND2")
		(14 "In6.Cu" signal "IN3")
		(16 "In7.Cu" signal "GND3")
		(18 "In8.Cu" signal "VCC")
		(20 "In9.Cu" signal "VCC1")
		(22 "In10.Cu" signal "GND4")
		(24 "In11.Cu" signal "IN4")
		(26 "In12.Cu" signal "GND5")
		(28 "In13.Cu" signal "IN5")
		(30 "In14.Cu" signal "GND6")
		(32 "In15.Cu" signal "IN6")
		(34 "In16.Cu" signal "GND7")
		(2 "B.Cu" signal "BOTTOM")
		(9 "F.Adhes" user "F.Adhesive")
		(11 "B.Adhes" user "B.Adhesive")
		(13 "F.Paste" user "Package Geometry/Pastemask Top")
		(15 "B.Paste" user "Package Geometry/Pastemask Bottom")
		(5 "F.SilkS" user "Ref Des/Silkscreen Top")
		(7 "B.SilkS" user "Ref Des/Silkscreen Bottom")
		(1 "F.Mask" user "Board Geometry/Soldermask Top")
		(3 "B.Mask" user "Board Geometry/Soldermask Bottom")
		(17 "Dwgs.User" user "User.Drawings")
		(19 "Cmts.User" user "User.Comments")
		(21 "Eco1.User" user "User.Eco1")
		(23 "Eco2.User" user "User.Eco2")
		(25 "Edge.Cuts" user "Board Geometry/Outline")
		(27 "Margin" user)
		(31 "F.CrtYd" user "Package Geometry/Place Bound Top")
		(29 "B.CrtYd" user "Package Geometry/Place Bound Bottom")
		(35 "F.Fab" user "Ref Des/Assembly Top")
		(33 "B.Fab" user "Ref Des/Assembly Bottom")
	)
	(footprint ""
		(layer "F.Cu")
		(at 298.342304 -426.478446 -90)
		(property "Reference" "R4138"
			(at 0 0 270)
			(layer "F.SilkS")
			(hide yes)
			(effects
				(font
					(size 1.27 1.27)
				)
			)
		)
		(property "Value" ""
			(at 0 0 270)
			(layer "F.Fab")
			(effects
				(font
					(size 1.27 1.27)
				)
			)
		)
		(duplicate_pad_numbers_are_jumpers no)
		(fp_line
			(start -0.7874 0.4064)
			(end -0.7874 -0.4064)
			(stroke
				(width 0.1524)
				(type default)
			)
			(layer "F.SilkS")
		)
		(fp_line
			(start 0.7874 0.4064)
			(end -0.7874 0.4064)
			(stroke
				(width 0.1524)
				(type default)
			)
			(layer "F.SilkS")
		)
		(fp_line
			(start -0.7874 -0.4064)
			(end 0.7874 -0.4064)
			(stroke
				(width 0.1524)
				(type default)
			)
			(layer "F.SilkS")
		)
		(fp_line
			(start 0.7874 -0.4064)
			(end 0.7874 0.4064)
			(stroke
				(width 0.1524)
				(type default)
			)
			(layer "F.SilkS")
		)
		(fp_line
			(start -0.67945 0.3048)
			(end -0.67945 -0.305054)
			(stroke
				(width 0.1)
				(type default)
			)
			(layer "F.Fab")
		)
		(fp_line
			(start -0.12065 0.3048)
			(end -0.67945 0.3048)
			(stroke
				(width 0.1)
				(type default)
			)
			(layer "F.Fab")
		)
		(fp_line
			(start 0.120396 0.3048)
			(end 0.120396 0.2794)
			(stroke
				(width 0.1)
				(type default)
			)
			(layer "F.Fab")
		)
		(fp_line
			(start 0.67945 0.3048)
			(end 0.120396 0.3048)
			(stroke
				(width 0.1)
				(type default)
			)
			(layer "F.Fab")
		)
		(fp_line
			(start -0.12065 0.2794)
			(end -0.12065 0.3048)
			(stroke
				(width 0.1)
				(type default)
			)
			(layer "F.Fab")
		)
		(fp_line
			(start 0.120396 0.2794)
			(end -0.12065 0.2794)
			(stroke
				(width 0.1)
				(type default)
			)
			(layer "F.Fab")
		)
		(fp_line
			(start -0.12065 -0.2794)
			(end 0.12065 -0.2794)
			(stroke
				(width 0.1)
				(type default)
			)
			(layer "F.Fab")
		)
		(fp_line
			(start 0.12065 -0.2794)
			(end 0.12065 -0.3048)
			(stroke
				(width 0.1)
				(type default)
			)
			(layer "F.Fab")
		)
		(fp_line
			(start 0.12065 -0.3048)
			(end 0.67945 -0.3048)
			(stroke
				(width 0.1)
				(type default)
			)
			(layer "F.Fab")
		)
		(fp_line
			(start 0.67945 -0.3048)
			(end 0.67945 0.3048)
			(stroke
				(width 0.1)
				(type default)
			)
			(layer "F.Fab")
		)
		(fp_line
			(start -0.67945 -0.305054)
			(end -0.12065 -0.305054)
			(stroke
				(width 0.1)
				(type default)
			)
			(layer "F.Fab")
		)
		(fp_line
			(start -0.12065 -0.305054)
			(end -0.12065 -0.2794)
			(stroke
				(width 0.1)
				(type default)
			)
			(layer "F.Fab")
		)
		(pad "1" smd circle
			(at -0.40005 0 270)
			(size 0 0)
			(layers "F.Cu" "F.Mask" "F.Paste")
			(net "P3V3_AUX")
		)
		(pad "2" smd circle
			(at 0.40005 0 270)
			(size 0 0)
			(layers "F.Cu" "F.Mask" "F.Paste")
			(net "GPU_3V3IO_RSVD5_FFU_N")
		)
	)
	(footprint ""
		(layer "F.Cu")
		(at 300.84395 -417.2204)
		(property "Reference" "R4573"
			(at 0 0 0)
			(layer "F.SilkS")
			(hide yes)
			(effects
				(font
					(size 1.27 1.27)
				)
			)
		)
		(property "Value" ""
			(at 0 0 0)
			(layer "F.Fab")
			(effects
				(font
					(size 1.27 1.27)
				)
			)
		)
		(duplicate_pad_numbers_are_jumpers no)
		(fp_line
			(start -0.7874 -0.4064)
			(end 0.7874 -0.4064)
			(stroke
				(width 0.1524)
				(type default)
			)
			(layer "F.SilkS")
		)
		(fp_line
			(start -0.7874 0.4064)
			(end -0.7874 -0.4064)
			(stroke
				(width 0.1524)
				(type default)
			)
			(layer "F.SilkS")
		)
		(fp_line
			(start 0.7874 -0.4064)
			(end 0.7874 0.4064)
			(stroke
				(width 0.1524)
				(type default)
			)
			(layer "F.SilkS")
		)
		(fp_line
			(start 0.7874 0.4064)
			(end -0.7874 0.4064)
			(stroke
				(width 0.1524)
				(type default)
			)
			(layer "F.SilkS")
		)
		(fp_line
			(start -0.67945 -0.305054)
			(end -0.12065 -0.305054)
			(stroke
				(width 0.1)
				(type default)
			)
			(layer "F.Fab")
		)
		(fp_line
			(start -0.67945 0.3048)
			(end -0.67945 -0.305054)
			(stroke
				(width 0.1)
				(type default)
			)
			(layer "F.Fab")
		)
		(fp_line
			(start -0.12065 -0.305054)
			(end -0.12065 -0.2794)
			(stroke
				(width 0.1)
				(type default)
			)
			(layer "F.Fab")
		)
		(fp_line
			(start -0.12065 -0.2794)
			(end 0.12065 -0.2794)
			(stroke
				(width 0.1)
				(type default)
			)
			(layer "F.Fab")
		)
		(fp_line
			(start -0.12065 0.2794)
			(end -0.12065 0.3048)
			(stroke
				(width 0.1)
				(type default)
			)
			(layer "F.Fab")
		)
		(fp_line
			(start -0.12065 0.3048)
			(end -0.67945 0.3048)
			(stroke
				(width 0.1)
				(type default)
			)
			(layer "F.Fab")
		)
		(fp_line
			(start 0.120396 0.2794)
			(end -0.12065 0.2794)
			(stroke
				(width 0.1)
				(type default)
			)
			(layer "F.Fab")
		)
		(fp_line
			(start 0.120396 0.3048)
			(end 0.120396 0.2794)
			(stroke
				(width 0.1)
				(type default)
			)
			(layer "F.Fab")
		)
		(fp_line
			(start 0.12065 -0.3048)
			(end 0.67945 -0.3048)
			(stroke
				(width 0.1)
				(type default)
			)
			(layer "F.Fab")
		)
		(fp_line
			(start 0.12065 -0.2794)
			(end 0.12065 -0.3048)
			(stroke
				(width 0.1)
				(type default)
			)
			(layer "F.Fab")
		)
		(fp_line
			(start 0.67945 -0.3048)
			(end 0.67945 0.3048)
			(stroke
				(width 0.1)
				(type default)
			)
			(layer "F.Fab")
		)
		(fp_line
			(start 0.67945 0.3048)
			(end 0.120396 0.3048)
			(stroke
				(width 0.1)
				(type default)
			)
			(layer "F.Fab")
		)
		(pad "1" smd circle
			(at -0.40005 0)
			(size 0 0)
			(layers "F.Cu" "F.Mask" "F.Paste")
			(net "PRSNT_CABLE_GPU_B3_N")
		)
		(pad "2" smd circle
			(at 0.40005 0)
			(size 0 0)
			(layers "F.Cu" "F.Mask" "F.Paste")
			(net "PRSNT_CABLE_GPU_B3_ISO_N")
		)
	)
)
